# S9S_MB_2U (Grand Teton) — schematic netlist excerpt (pin names and nets, part order shuffled) for the footprints in the layout excerpt that follows; sources: Cadence DE-HDL packaged netlist, KiCad conversion of 03242023_DA0F0TMBIJ0_F0T_Motherboard_J_brd_V01_OCP.brd

PJ54  Q_SHORT  EMPTY  pkg SM  page 278 : \1\ = VSENSE_PVCCD_HV_CPU0_DP ; \2\ = SH_PVCCD_HV_CPU0
PC299_P0_1  Q_CAP  1UF 16V 10% X6S  pkg C0402  page 267 : A = SW_P12V_PVCCIN_CPU0_FLT ; B = GND
C306  Q_CAP  22UF 4V 20% X6S  pkg C0402  page 77 : A = PVCCIN_CPU1 ; B = GND

(kicad_pcb
	(version 20260206)
	(generator "pcbnew")
	(generator_version "10.0")
	(general
		(thickness 1.6)
		(legacy_teardrops no)
	)
	(paper "A4")
	(title_block
		(title "03242023_DA0F0TMBIJ0_F0T_Motherboard_J_brd_V01_OCP.brd")
		(comment 1 "Grand Teton / footprints 3838-3840 of 6105")
	)
	(layers
		(0 "F.Cu" signal "TOP")
		(4 "In1.Cu" signal "GND")
		(6 "In2.Cu" signal "IN1")
		(8 "In3.Cu" signal "GND1")
		(10 "In4.Cu" signal "IN2")
		(12 "In5.Cu" signal "GND2")
		(14 "In6.Cu" signal "IN3")
		(16 "In7.Cu" signal "GND3")
		(18 "In8.Cu" signal "VCC")
		(20 "In9.Cu" signal "VCC1")
		(22 "In10.Cu" signal "GND4")
		(24 "In11.Cu" signal "IN4")
		(26 "In12.Cu" signal "GND5")
		(28 "In13.Cu" signal "IN5")
		(30 "In14.Cu" signal "GND6")
		(32 "In15.Cu" signal "IN6")
		(34 "In16.Cu" signal "GND7")
		(2 "B.Cu" signal "BOTTOM")
		(9 "F.Adhes" user "F.Adhesive")
		(11 "B.Adhes" user "B.Adhesive")
		(13 "F.Paste" user "Package Geometry/Pastemask Top")
		(15 "B.Paste" user "Package Geometry/Pastemask Bottom")
		(5 "F.SilkS" user "Ref Des/Silkscreen Top")
		(7 "B.SilkS" user "Ref Des/Silkscreen Bottom")
		(1 "F.Mask" user "Board Geometry/Soldermask Top")
		(3 "B.Mask" user "Board Geometry/Soldermask Bottom")
		(17 "Dwgs.User" user "User.Drawings")
		(19 "Cmts.User" user "User.Comments")
		(21 "Eco1.User" user "User.Eco1")
		(23 "Eco2.User" user "User.Eco2")
		(25 "Edge.Cuts" user "Board Geometry/Outline")
		(27 "Margin" user)
		(31 "F.CrtYd" user "Package Geometry/Place Bound Top")
		(29 "B.CrtYd" user "Package Geometry/Place Bound Bottom")
		(35 "F.Fab" user "Ref Des/Assembly Top")
		(33 "B.Fab" user "Ref Des/Assembly Bottom")
	)
	(footprint ""
		(layer "F.Cu")
		(at 348.506796 -333.804514 -90)
		(property "Reference" "PC299_P0_1"
			(at 0 0 270)
			(layer "F.SilkS")
			(hide yes)
			(effects
				(font
					(size 1.27 1.27)
				)
			)
		)
		(property "Value" ""
			(at 0 0 270)
			(layer "F.Fab")
			(effects
				(font
					(size 1.27 1.27)
				)
			)
		)
		(duplicate_pad_numbers_are_jumpers no)
		(fp_line
			(start -0.7874 0.4064)
			(end -0.7874 -0.4064)
			(stroke
				(width 0.1524)
				(type default)
			)
			(layer "F.SilkS")
		)
		(fp_line
			(start 0.7874 0.4064)
			(end -0.7874 0.4064)
			(stroke
				(width 0.1524)
				(type default)
			)
			(layer "F.SilkS")
		)
		(fp_line
			(start -0.7874 -0.4064)
			(end 0.7874 -0.4064)
			(stroke
				(width 0.1524)
				(type default)
			)
			(layer "F.SilkS")
		)
		(fp_line
			(start 0.7874 -0.4064)
			(end 0.7874 0.4064)
			(stroke
				(width 0.1524)
				(type default)
			)
			(layer "F.SilkS")
		)
		(fp_line
			(start -0.67945 0.3048)
			(end -0.67945 -0.305054)
			(stroke
				(width 0.1)
				(type default)
			)
			(layer "F.Fab")
		)
		(fp_line
			(start -0.12065 0.3048)
			(end -0.67945 0.3048)
			(stroke
				(width 0.1)
				(type default)
			)
			(layer "F.Fab")
		)
		(fp_line
			(start 0.120396 0.3048)
			(end 0.120396 0.2794)
			(stroke
				(width 0.1)
				(type default)
			)
			(layer "F.Fab")
		)
		(fp_line
			(start 0.67945 0.3048)
			(end 0.120396 0.3048)
			(stroke
				(width 0.1)
				(type default)
			)
			(layer "F.Fab")
		)
		(fp_line
			(start -0.12065 0.2794)
			(end -0.12065 0.3048)
			(stroke
				(width 0.1)
				(type default)
			)
			(layer "F.Fab")
		)
		(fp_line
			(start 0.120396 0.2794)
			(end -0.12065 0.2794)
			(stroke
				(width 0.1)
				(type default)
			)
			(layer "F.Fab")
		)
		(fp_line
			(start -0.12065 -0.2794)
			(end 0.12065 -0.2794)
			(stroke
				(width 0.1)
				(type default)
			)
			(layer "F.Fab")
		)
		(fp_line
			(start 0.12065 -0.2794)
			(end 0.12065 -0.3048)
			(stroke
				(width 0.1)
				(type default)
			)
			(layer "F.Fab")
		)
		(fp_line
			(start 0.12065 -0.3048)
			(end 0.67945 -0.3048)
			(stroke
				(width 0.1)
				(type default)
			)
			(layer "F.Fab")
		)
		(fp_line
			(start 0.67945 -0.3048)
			(end 0.67945 0.3048)
			(stroke
				(width 0.1)
				(type default)
			)
			(layer "F.Fab")
		)
		(fp_line
			(start -0.67945 -0.305054)
			(end -0.12065 -0.305054)
			(stroke
				(width 0.1)
				(type default)
			)
			(layer "F.Fab")
		)
		(fp_line
			(start -0.12065 -0.305054)
			(end -0.12065 -0.2794)
			(stroke
				(width 0.1)
				(type default)
			)
			(layer "F.Fab")
		)
		(pad "1" smd circle
			(at -0.40005 0 270)
			(size 0 0)
			(layers "F.Cu" "F.Mask" "F.Paste")
			(net "SW_P12V_PVCCIN_CPU0_FLT")
		)
		(pad "2" smd circle
			(at 0.40005 0 270)
			(size 0 0)
			(layers "F.Cu" "F.Mask" "F.Paste")
			(net "GND")
		)
	)
	(footprint ""
		(layer "F.Cu")
		(at 117.526816 -258.72694 90)
		(property "Reference" "C306"
			(at 0 0 90)
			(layer "F.SilkS")
			(hide yes)
			(effects
				(font
					(size 1.27 1.27)
				)
			)
		)
		(property "Value" ""
			(at 0 0 90)
			(layer "F.Fab")
			(effects
				(font
					(size 1.27 1.27)
				)
			)
		)
		(duplicate_pad_numbers_are_jumpers no)
		(fp_line
			(start 0.7874 -0.4064)
			(end 0.7874 0.4064)
			(stroke
				(width 0.1524)
				(type default)
			)
			(layer "F.SilkS")
		)
		(fp_line
			(start -0.7874 -0.4064)
			(end 0.7874 -0.4064)
			(stroke
				(width 0.1524)
				(type default)
			)
			(layer "F.SilkS")
		)
		(fp_line
			(start 0.7874 0.4064)
			(end -0.7874 0.4064)
			(stroke
				(width 0.1524)
				(type default)
			)
			(layer "F.SilkS")
		)
		(fp_line
			(start -0.7874 0.4064)
			(end -0.7874 -0.4064)
			(stroke
				(width 0.1524)
				(type default)
			)
			(layer "F.SilkS")
		)
		(fp_line
			(start -0.12065 -0.305054)
			(end -0.12065 -0.2794)
			(stroke
				(width 0.1)
				(type default)
			)
			(layer "F.Fab")
		)
		(fp_line
			(start -0.67945 -0.305054)
			(end -0.12065 -0.305054)
			(stroke
				(width 0.1)
				(type default)
			)
			(layer "F.Fab")
		)
		(fp_line
			(start 0.67945 -0.3048)
			(end 0.67945 0.3048)
			(stroke
				(width 0.1)
				(type default)
			)
			(layer "F.Fab")
		)
		(fp_line
			(start 0.12065 -0.3048)
			(end 0.67945 -0.3048)
			(stroke
				(width 0.1)
				(type default)
			)
			(layer "F.Fab")
		)
		(fp_line
			(start 0.12065 -0.2794)
			(end 0.12065 -0.3048)
			(stroke
				(width 0.1)
				(type default)
			)
			(layer "F.Fab")
		)
		(fp_line
			(start -0.12065 -0.2794)
			(end 0.12065 -0.2794)
			(stroke
				(width 0.1)
				(type default)
			)
			(layer "F.Fab")
		)
		(fp_line
			(start 0.120396 0.2794)
			(end -0.12065 0.2794)
			(stroke
				(width 0.1)
				(type default)
			)
			(layer "F.Fab")
		)
		(fp_line
			(start -0.12065 0.2794)
			(end -0.12065 0.3048)
			(stroke
				(width 0.1)
				(type default)
			)
			(layer "F.Fab")
		)
		(fp_line
			(start 0.67945 0.3048)
			(end 0.120396 0.3048)
			(stroke
				(width 0.1)
				(type default)
			)
			(layer "F.Fab")
		)
		(fp_line
			(start 0.120396 0.3048)
			(end 0.120396 0.2794)
			(stroke
				(width 0.1)
				(type default)
			)
			(layer "F.Fab")
		)
		(fp_line
			(start -0.12065 0.3048)
			(end -0.67945 0.3048)
			(stroke
				(width 0.1)
				(type default)
			)
			(layer "F.Fab")
		)
		(fp_line
			(start -0.67945 0.3048)
			(end -0.67945 -0.305054)
			(stroke
				(width 0.1)
				(type default)
			)
			(layer "F.Fab")
		)
		(pad "1" smd circle
			(at -0.40005 0 90)
			(size 0 0)
			(layers "F.Cu" "F.Mask" "F.Paste")
			(net "PVCCIN_CPU1")
		)
		(pad "2" smd circle
			(at 0.40005 0 90)
			(size 0 0)
			(layers "F.Cu" "F.Mask" "F.Paste")
			(net "GND")
		)
	)
	(footprint ""
		(layer "F.Cu")
		(at 435.588664 -128.877314)
		(property "Reference" "PJ54"
			(at 0.826516 -1.260856 0)
			(unlocked yes)
			(layer "F.SilkS")
			(effects
				(font
					(size 0.7874 0.5842)
					(thickness 0.1524)
				)
				(justify left)
			)
		)
		(property "Value" ""
			(at 0 0 0)
			(layer "F.Fab")
			(effects
				(font
					(size 1.27 1.27)
				)
			)
		)
		(duplicate_pad_numbers_are_jumpers no)
		(pad "1" smd circle
			(at -0.7493 0 90)
			(size 0 0)
			(layers "F.Cu" "F.Mask" "F.Paste")
			(net "VSENSE_PVCCD_HV_CPU0_DP")
		)
		(pad "2" smd rect
			(at 0.7493 0 270)
			(size 0.7112 0.8128)
			(layers "F.Cu" "F.Mask" "F.Paste")
			(net "SH_PVCCD_HV_CPU0")
		)
		(zone
			(layer "F.Cu")
			(hatch none 0.5)
			(connect_pads
				(clearance 0)
			)
			(min_thickness 0.25)
			(keepout
				(tracks allowed)
				(vias not_allowed)
				(pads allowed)
				(copperpour not_allowed)
				(footprints allowed)
			)
			(placement
				(enabled no)
				(sheetname "")
			)
			(fill
				(thermal_gap 0.5)
				(thermal_bridge_width 0.5)
				(island_removal_mode 0)
			)
			(polygon
				(pts
					(xy 434.407564 -128.466088) (xy 436.795164 -128.466088) (xy 436.795164 -129.283714) (xy 434.407564 -129.283714)
				)
			)
		)
	)
)
